(kicad_pcb
	(version 20260206)
	(generator "pcbnew")
	(generator_version "10.0")
	(general
		(thickness 1.6)
		(legacy_teardrops no)
	)
	(paper "A4")
	(title_block
		(title "04192023_DAF0TMB3IC0_F0TG_MB_C_brd_V02_OCP.brd")
		(comment 1 "Grand Teton / footprint 4371 of 8354 (J26), pads 114-226 of 291")
	)
	(layers
		(0 "F.Cu" signal "TOP")
		(4 "In1.Cu" signal "GND")
		(6 "In2.Cu" signal "IN1")
		(8 "In3.Cu" signal "GND1")
		(10 "In4.Cu" signal "IN2")
		(12 "In5.Cu" signal "GND2")
		(14 "In6.Cu" signal "IN3")
		(16 "In7.Cu" signal "GND3")
		(18 "In8.Cu" signal "VCC")
		(20 "In9.Cu" signal "VCC1")
		(22 "In10.Cu" signal "GND4")
		(24 "In11.Cu" signal "IN4")
		(26 "In12.Cu" signal "GND5")
		(28 "In13.Cu" signal "IN5")
		(30 "In14.Cu" signal "GND6")
		(32 "In15.Cu" signal "IN6")
		(34 "In16.Cu" signal "GND7")
		(2 "B.Cu" signal "BOTTOM")
		(9 "F.Adhes" user "F.Adhesive")
		(11 "B.Adhes" user "B.Adhesive")
		(13 "F.Paste" user "Package Geometry/Pastemask Top")
		(15 "B.Paste" user "Package Geometry/Pastemask Bottom")
		(5 "F.SilkS" user "Ref Des/Silkscreen Top")
		(7 "B.SilkS" user "Ref Des/Silkscreen Bottom")
		(1 "F.Mask" user "Board Geometry/Soldermask Top")
		(3 "B.Mask" user "Board Geometry/Soldermask Bottom")
		(17 "Dwgs.User" user "User.Drawings")
		(19 "Cmts.User" user "User.Comments")
		(21 "Eco1.User" user "User.Eco1")
		(23 "Eco2.User" user "User.Eco2")
		(25 "Edge.Cuts" user "Board Geometry/Outline")
		(27 "Margin" user)
		(31 "F.CrtYd" user "Package Geometry/Place Bound Top")
		(29 "B.CrtYd" user "Package Geometry/Place Bound Bottom")
		(35 "F.Fab" user "Ref Des/Assembly Top")
		(33 "B.Fab" user "Ref Des/Assembly Bottom")
	)
	(footprint ""
		(layer "F.Cu")
		(at 49.834038 -255.560322 180)
		(property "Reference" "J26"
			(at -0.703326 -82.357722 0)
			(unlocked yes)
			(layer "F.SilkS")
			(effects
				(font
					(size 0.7874 0.5842)
					(thickness 0.1524)
				)
			)
		)
		(property "Value" ""
			(at 0 0 180)
			(layer "F.Fab")
			(effects
				(font
					(size 1.27 1.27)
				)
			)
		)
		(duplicate_pad_numbers_are_jumpers no)
		(pad "114" smd rect
			(at -2.050034 37.824918 90)
			(size 0.519938 1.4986)
			(layers "F.Cu" "F.Mask" "F.Paste")
			(net "GND")
		)
		(pad "115" smd rect
			(at -2.050034 38.675056 90)
			(size 0.519938 1.4986)
			(layers "F.Cu" "F.Mask" "F.Paste")
			(net "M_B_CPU1_SB_DQS_DP<1>")
		)
		(pad "116" smd rect
			(at -2.050034 39.52494 90)
			(size 0.519938 1.4986)
			(layers "F.Cu" "F.Mask" "F.Paste")
			(net "M_B_CPU1_SB_DQS_DN<1>")
		)
		(pad "117" smd rect
			(at -2.050034 40.375078 90)
			(size 0.519938 1.4986)
			(layers "F.Cu" "F.Mask" "F.Paste")
			(net "GND")
		)
		(pad "118" smd rect
			(at -2.050034 41.224962 90)
			(size 0.519938 1.4986)
			(layers "F.Cu" "F.Mask" "F.Paste")
			(net "M_B_CPU1_SB_DQ<12>")
		)
		(pad "119" smd rect
			(at -2.050034 42.0751 90)
			(size 0.519938 1.4986)
			(layers "F.Cu" "F.Mask" "F.Paste")
			(net "GND")
		)
		(pad "120" smd rect
			(at -2.050034 42.924984 90)
			(size 0.519938 1.4986)
			(layers "F.Cu" "F.Mask" "F.Paste")
			(net "M_B_CPU1_SB_DQ<13>")
		)
		(pad "121" smd rect
			(at -2.050034 43.775122 90)
			(size 0.519938 1.4986)
			(layers "F.Cu" "F.Mask" "F.Paste")
			(net "GND")
		)
		(pad "122" smd rect
			(at -2.050034 44.625006 90)
			(size 0.519938 1.4986)
			(layers "F.Cu" "F.Mask" "F.Paste")
			(net "M_B_CPU1_SB_DQ<16>")
		)
		(pad "123" smd rect
			(at -2.050034 45.47489 90)
			(size 0.519938 1.4986)
			(layers "F.Cu" "F.Mask" "F.Paste")
			(net "GND")
		)
		(pad "124" smd rect
			(at -2.050034 46.325028 90)
			(size 0.519938 1.4986)
			(layers "F.Cu" "F.Mask" "F.Paste")
			(net "M_B_CPU1_SB_DQ<17>")
		)
		(pad "125" smd rect
			(at -2.050034 47.174912 90)
			(size 0.519938 1.4986)
			(layers "F.Cu" "F.Mask" "F.Paste")
			(net "GND")
		)
		(pad "126" smd rect
			(at -2.050034 48.02505 90)
			(size 0.519938 1.4986)
			(layers "F.Cu" "F.Mask" "F.Paste")
			(net "M_B_CPU1_SB_DQS_DP<2>")
		)
		(pad "127" smd rect
			(at -2.050034 48.874934 90)
			(size 0.519938 1.4986)
			(layers "F.Cu" "F.Mask" "F.Paste")
			(net "M_B_CPU1_SB_DQS_DN<2>")
		)
		(pad "128" smd rect
			(at -2.050034 49.725072 90)
			(size 0.519938 1.4986)
			(layers "F.Cu" "F.Mask" "F.Paste")
			(net "GND")
		)
		(pad "129" smd rect
			(at -2.050034 50.574956 90)
			(size 0.519938 1.4986)
			(layers "F.Cu" "F.Mask" "F.Paste")
			(net "M_B_CPU1_SB_DQ<20>")
		)
		(pad "130" smd rect
			(at -2.050034 51.425094 90)
			(size 0.519938 1.4986)
			(layers "F.Cu" "F.Mask" "F.Paste")
			(net "GND")
		)
		(pad "131" smd rect
			(at -2.050034 52.274978 90)
			(size 0.519938 1.4986)
			(layers "F.Cu" "F.Mask" "F.Paste")
			(net "M_B_CPU1_SB_DQ<21>")
		)
		(pad "132" smd rect
			(at -2.050034 53.125116 90)
			(size 0.519938 1.4986)
			(layers "F.Cu" "F.Mask" "F.Paste")
			(net "GND")
		)
		(pad "133" smd rect
			(at -2.050034 53.975 90)
			(size 0.519938 1.4986)
			(layers "F.Cu" "F.Mask" "F.Paste")
			(net "M_B_CPU1_SB_DQ<24>")
		)
		(pad "134" smd rect
			(at -2.050034 54.824884 90)
			(size 0.519938 1.4986)
			(layers "F.Cu" "F.Mask" "F.Paste")
			(net "GND")
		)
		(pad "135" smd rect
			(at -2.050034 55.675022 90)
			(size 0.519938 1.4986)
			(layers "F.Cu" "F.Mask" "F.Paste")
			(net "M_B_CPU1_SB_DQ<25>")
		)
		(pad "136" smd rect
			(at -2.050034 56.524906 90)
			(size 0.519938 1.4986)
			(layers "F.Cu" "F.Mask" "F.Paste")
			(net "GND")
		)
		(pad "137" smd rect
			(at -2.050034 57.375044 90)
			(size 0.519938 1.4986)
			(layers "F.Cu" "F.Mask" "F.Paste")
			(net "M_B_CPU1_SB_DQS_DP<3>")
		)
		(pad "138" smd rect
			(at -2.050034 58.224928 90)
			(size 0.519938 1.4986)
			(layers "F.Cu" "F.Mask" "F.Paste")
			(net "M_B_CPU1_SB_DQS_DN<3>")
		)
		(pad "139" smd rect
			(at -2.050034 59.075066 90)
			(size 0.519938 1.4986)
			(layers "F.Cu" "F.Mask" "F.Paste")
			(net "GND")
		)
		(pad "140" smd rect
			(at -2.050034 59.92495 90)
			(size 0.519938 1.4986)
			(layers "F.Cu" "F.Mask" "F.Paste")
			(net "M_B_CPU1_SB_DQ<28>")
		)
		(pad "141" smd rect
			(at -2.050034 60.775088 90)
			(size 0.519938 1.4986)
			(layers "F.Cu" "F.Mask" "F.Paste")
			(net "GND")
		)
		(pad "142" smd rect
			(at -2.050034 61.624972 90)
			(size 0.519938 1.4986)
			(layers "F.Cu" "F.Mask" "F.Paste")
			(net "M_B_CPU1_SB_DQ<29>")
		)
		(pad "143" smd rect
			(at -2.050034 62.47511 90)
			(size 0.519938 1.4986)
			(layers "F.Cu" "F.Mask" "F.Paste")
			(net "GND")
		)
		(pad "144" smd rect
			(at -2.050034 63.324994 90)
			(size 0.519938 1.4986)
			(layers "F.Cu" "F.Mask" "F.Paste")
			(net "Net_2271")
		)
		(pad "145" smd rect
			(at 2.050034 -63.324994 90)
			(size 0.519938 1.4986)
			(layers "F.Cu" "F.Mask" "F.Paste")
			(net "P12V_MEM_CPU1")
		)
		(pad "146" smd rect
			(at 2.050034 -62.47511 90)
			(size 0.519938 1.4986)
			(layers "F.Cu" "F.Mask" "F.Paste")
			(net "P12V_MEM_CPU1")
		)
		(pad "147" smd rect
			(at 2.050034 -61.624972 90)
			(size 0.519938 1.4986)
			(layers "F.Cu" "F.Mask" "F.Paste")
			(net "PWRGD_CHB_CPU1_DIMM")
		)
		(pad "148" smd rect
			(at 2.050034 -60.775088 90)
			(size 0.519938 1.4986)
			(layers "F.Cu" "F.Mask" "F.Paste")
			(net "PD_CHB_CPU1_DIMM_SAA")
		)
		(pad "149" smd rect
			(at 2.050034 -59.92495 90)
			(size 0.519938 1.4986)
			(layers "F.Cu" "F.Mask" "F.Paste")
			(net "Net_2272")
		)
		(pad "150" smd rect
			(at 2.050034 -59.075066 90)
			(size 0.519938 1.4986)
			(layers "F.Cu" "F.Mask" "F.Paste")
			(net "Net_2273")
		)
		(pad "151" smd rect
			(at 2.050034 -58.224928 90)
			(size 0.519938 1.4986)
			(layers "F.Cu" "F.Mask" "F.Paste")
			(net "GND")
		)
		(pad "152" smd rect
			(at 2.050034 -57.375044 90)
			(size 0.519938 1.4986)
			(layers "F.Cu" "F.Mask" "F.Paste")
			(net "M_B_CPU1_SA_DQ<2>")
		)
		(pad "153" smd rect
			(at 2.050034 -56.524906 90)
			(size 0.519938 1.4986)
			(layers "F.Cu" "F.Mask" "F.Paste")
			(net "GND")
		)
		(pad "154" smd rect
			(at 2.050034 -55.675022 90)
			(size 0.519938 1.4986)
			(layers "F.Cu" "F.Mask" "F.Paste")
			(net "M_B_CPU1_SA_DQ<3>")
		)
		(pad "155" smd rect
			(at 2.050034 -54.824884 90)
			(size 0.519938 1.4986)
			(layers "F.Cu" "F.Mask" "F.Paste")
			(net "GND")
		)
		(pad "156" smd rect
			(at 2.050034 -53.975 90)
			(size 0.519938 1.4986)
			(layers "F.Cu" "F.Mask" "F.Paste")
			(net "M_B_CPU1_SA_DQS_DN<5>")
		)
		(pad "157" smd rect
			(at 2.050034 -53.125116 90)
			(size 0.519938 1.4986)
			(layers "F.Cu" "F.Mask" "F.Paste")
			(net "M_B_CPU1_SA_DQS_DP<5>")
		)
		(pad "158" smd rect
			(at 2.050034 -52.274978 90)
			(size 0.519938 1.4986)
			(layers "F.Cu" "F.Mask" "F.Paste")
			(net "GND")
		)
		(pad "159" smd rect
			(at 2.050034 -51.425094 90)
			(size 0.519938 1.4986)
			(layers "F.Cu" "F.Mask" "F.Paste")
			(net "M_B_CPU1_SA_DQ<6>")
		)
		(pad "160" smd rect
			(at 2.050034 -50.574956 90)
			(size 0.519938 1.4986)
			(layers "F.Cu" "F.Mask" "F.Paste")
			(net "GND")
		)
		(pad "161" smd rect
			(at 2.050034 -49.725072 90)
			(size 0.519938 1.4986)
			(layers "F.Cu" "F.Mask" "F.Paste")
			(net "M_B_CPU1_SA_DQ<7>")
		)
		(pad "162" smd rect
			(at 2.050034 -48.874934 90)
			(size 0.519938 1.4986)
			(layers "F.Cu" "F.Mask" "F.Paste")
			(net "GND")
		)
		(pad "163" smd rect
			(at 2.050034 -48.02505 90)
			(size 0.519938 1.4986)
			(layers "F.Cu" "F.Mask" "F.Paste")
			(net "M_B_CPU1_SA_DQ<10>")
		)
		(pad "164" smd rect
			(at 2.050034 -47.174912 90)
			(size 0.519938 1.4986)
			(layers "F.Cu" "F.Mask" "F.Paste")
			(net "GND")
		)
		(pad "165" smd rect
			(at 2.050034 -46.325028 90)
			(size 0.519938 1.4986)
			(layers "F.Cu" "F.Mask" "F.Paste")
			(net "M_B_CPU1_SA_DQ<11>")
		)
		(pad "166" smd rect
			(at 2.050034 -45.47489 90)
			(size 0.519938 1.4986)
			(layers "F.Cu" "F.Mask" "F.Paste")
			(net "GND")
		)
		(pad "167" smd rect
			(at 2.050034 -44.625006 90)
			(size 0.519938 1.4986)
			(layers "F.Cu" "F.Mask" "F.Paste")
			(net "M_B_CPU1_SA_DQS_DN<6>")
		)
		(pad "168" smd rect
			(at 2.050034 -43.775122 90)
			(size 0.519938 1.4986)
			(layers "F.Cu" "F.Mask" "F.Paste")
			(net "M_B_CPU1_SA_DQS_DP<6>")
		)
		(pad "169" smd rect
			(at 2.050034 -42.924984 90)
			(size 0.519938 1.4986)
			(layers "F.Cu" "F.Mask" "F.Paste")
			(net "GND")
		)
		(pad "170" smd rect
			(at 2.050034 -42.0751 90)
			(size 0.519938 1.4986)
			(layers "F.Cu" "F.Mask" "F.Paste")
			(net "M_B_CPU1_SA_DQ<14>")
		)
		(pad "171" smd rect
			(at 2.050034 -41.224962 90)
			(size 0.519938 1.4986)
			(layers "F.Cu" "F.Mask" "F.Paste")
			(net "GND")
		)
		(pad "172" smd rect
			(at 2.050034 -40.375078 90)
			(size 0.519938 1.4986)
			(layers "F.Cu" "F.Mask" "F.Paste")
			(net "M_B_CPU1_SA_DQ<15>")
		)
		(pad "173" smd rect
			(at 2.050034 -39.52494 90)
			(size 0.519938 1.4986)
			(layers "F.Cu" "F.Mask" "F.Paste")
			(net "GND")
		)
		(pad "174" smd rect
			(at 2.050034 -38.675056 90)
			(size 0.519938 1.4986)
			(layers "F.Cu" "F.Mask" "F.Paste")
			(net "M_B_CPU1_SA_DQ<18>")
		)
		(pad "175" smd rect
			(at 2.050034 -37.824918 90)
			(size 0.519938 1.4986)
			(layers "F.Cu" "F.Mask" "F.Paste")
			(net "GND")
		)
		(pad "176" smd rect
			(at 2.050034 -36.975034 90)
			(size 0.519938 1.4986)
			(layers "F.Cu" "F.Mask" "F.Paste")
			(net "M_B_CPU1_SA_DQ<19>")
		)
		(pad "177" smd rect
			(at 2.050034 -36.124896 90)
			(size 0.519938 1.4986)
			(layers "F.Cu" "F.Mask" "F.Paste")
			(net "GND")
		)
		(pad "178" smd rect
			(at 2.050034 -35.275012 90)
			(size 0.519938 1.4986)
			(layers "F.Cu" "F.Mask" "F.Paste")
			(net "M_B_CPU1_SA_DQS_DN<7>")
		)
		(pad "179" smd rect
			(at 2.050034 -34.425128 90)
			(size 0.519938 1.4986)
			(layers "F.Cu" "F.Mask" "F.Paste")
			(net "M_B_CPU1_SA_DQS_DP<7>")
		)
		(pad "180" smd rect
			(at 2.050034 -33.57499 90)
			(size 0.519938 1.4986)
			(layers "F.Cu" "F.Mask" "F.Paste")
			(net "GND")
		)
		(pad "181" smd rect
			(at 2.050034 -32.725106 90)
			(size 0.519938 1.4986)
			(layers "F.Cu" "F.Mask" "F.Paste")
			(net "M_B_CPU1_SA_DQ<22>")
		)
		(pad "182" smd rect
			(at 2.050034 -31.874968 90)
			(size 0.519938 1.4986)
			(layers "F.Cu" "F.Mask" "F.Paste")
			(net "GND")
		)
		(pad "183" smd rect
			(at 2.050034 -31.025084 90)
			(size 0.519938 1.4986)
			(layers "F.Cu" "F.Mask" "F.Paste")
			(net "M_B_CPU1_SA_DQ<23>")
		)
		(pad "184" smd rect
			(at 2.050034 -30.174946 90)
			(size 0.519938 1.4986)
			(layers "F.Cu" "F.Mask" "F.Paste")
			(net "GND")
		)
		(pad "185" smd rect
			(at 2.050034 -29.325062 90)
			(size 0.519938 1.4986)
			(layers "F.Cu" "F.Mask" "F.Paste")
			(net "M_B_CPU1_SA_DQ<26>")
		)
		(pad "186" smd rect
			(at 2.050034 -28.474924 90)
			(size 0.519938 1.4986)
			(layers "F.Cu" "F.Mask" "F.Paste")
			(net "GND")
		)
		(pad "187" smd rect
			(at 2.050034 -27.62504 90)
			(size 0.519938 1.4986)
			(layers "F.Cu" "F.Mask" "F.Paste")
			(net "M_B_CPU1_SA_DQ<27>")
		)
		(pad "188" smd rect
			(at 2.050034 -26.774902 90)
			(size 0.519938 1.4986)
			(layers "F.Cu" "F.Mask" "F.Paste")
			(net "GND")
		)
		(pad "189" smd rect
			(at 2.050034 -25.925018 90)
			(size 0.519938 1.4986)
			(layers "F.Cu" "F.Mask" "F.Paste")
			(net "M_B_CPU1_SA_DQS_DN<8>")
		)
		(pad "190" smd rect
			(at 2.050034 -25.07488 90)
			(size 0.519938 1.4986)
			(layers "F.Cu" "F.Mask" "F.Paste")
			(net "M_B_CPU1_SA_DQS_DP<8>")
		)
		(pad "191" smd rect
			(at 2.050034 -24.224996 90)
			(size 0.519938 1.4986)
			(layers "F.Cu" "F.Mask" "F.Paste")
			(net "GND")
		)
		(pad "192" smd rect
			(at 2.050034 -23.375112 90)
			(size 0.519938 1.4986)
			(layers "F.Cu" "F.Mask" "F.Paste")
			(net "M_B_CPU1_SA_DQ<30>")
		)
		(pad "193" smd rect
			(at 2.050034 -22.524974 90)
			(size 0.519938 1.4986)
			(layers "F.Cu" "F.Mask" "F.Paste")
			(net "GND")
		)
		(pad "194" smd rect
			(at 2.050034 -21.67509 90)
			(size 0.519938 1.4986)
			(layers "F.Cu" "F.Mask" "F.Paste")
			(net "M_B_CPU1_SA_DQ<31>")
		)
		(pad "195" smd rect
			(at 2.050034 -20.824952 90)
			(size 0.519938 1.4986)
			(layers "F.Cu" "F.Mask" "F.Paste")
			(net "GND")
		)
		(pad "196" smd rect
			(at 2.050034 -19.975068 90)
			(size 0.519938 1.4986)
			(layers "F.Cu" "F.Mask" "F.Paste")
			(net "M_B_CPU1_SA_CB<2>")
		)
		(pad "197" smd rect
			(at 2.050034 -19.12493 90)
			(size 0.519938 1.4986)
			(layers "F.Cu" "F.Mask" "F.Paste")
			(net "GND")
		)
		(pad "198" smd rect
			(at 2.050034 -18.275046 90)
			(size 0.519938 1.4986)
			(layers "F.Cu" "F.Mask" "F.Paste")
			(net "M_B_CPU1_SA_CB<3>")
		)
		(pad "199" smd rect
			(at 2.050034 -17.424908 90)
			(size 0.519938 1.4986)
			(layers "F.Cu" "F.Mask" "F.Paste")
			(net "GND")
		)
		(pad "200" smd rect
			(at 2.050034 -16.575024 90)
			(size 0.519938 1.4986)
			(layers "F.Cu" "F.Mask" "F.Paste")
			(net "M_B_CPU1_SA_DQS_DN<9>")
		)
		(pad "201" smd rect
			(at 2.050034 -15.724886 90)
			(size 0.519938 1.4986)
			(layers "F.Cu" "F.Mask" "F.Paste")
			(net "M_B_CPU1_SA_DQS_DP<9>")
		)
		(pad "202" smd rect
			(at 2.050034 -14.875002 90)
			(size 0.519938 1.4986)
			(layers "F.Cu" "F.Mask" "F.Paste")
			(net "GND")
		)
		(pad "203" smd rect
			(at 2.050034 -14.025118 90)
			(size 0.519938 1.4986)
			(layers "F.Cu" "F.Mask" "F.Paste")
			(net "M_B_CPU1_SA_CB<6>")
		)
		(pad "204" smd rect
			(at 2.050034 -13.17498 90)
			(size 0.519938 1.4986)
			(layers "F.Cu" "F.Mask" "F.Paste")
			(net "GND")
		)
		(pad "205" smd rect
			(at 2.050034 -12.325096 90)
			(size 0.519938 1.4986)
			(layers "F.Cu" "F.Mask" "F.Paste")
			(net "M_B_CPU1_SA_CB<7>")
		)
		(pad "206" smd rect
			(at 2.050034 -11.474958 90)
			(size 0.519938 1.4986)
			(layers "F.Cu" "F.Mask" "F.Paste")
			(net "GND")
		)
		(pad "207" smd rect
			(at 2.050034 -10.625074 90)
			(size 0.519938 1.4986)
			(layers "F.Cu" "F.Mask" "F.Paste")
			(net "M_B_CPU1_RESET_N")
		)
		(pad "208" smd rect
			(at 2.050034 -9.774936 90)
			(size 0.519938 1.4986)
			(layers "F.Cu" "F.Mask" "F.Paste")
			(net "GND")
		)
		(pad "209" smd rect
			(at 2.050034 -8.925052 90)
			(size 0.519938 1.4986)
			(layers "F.Cu" "F.Mask" "F.Paste")
			(net "M_B_CPU1_SA_CS_N<1>")
		)
		(pad "210" smd rect
			(at 2.050034 -8.074914 90)
			(size 0.519938 1.4986)
			(layers "F.Cu" "F.Mask" "F.Paste")
			(net "GND")
		)
		(pad "211" smd rect
			(at 2.050034 -7.22503 90)
			(size 0.519938 1.4986)
			(layers "F.Cu" "F.Mask" "F.Paste")
			(net "M_B_CPU1_SA_CA<1>")
		)
		(pad "212" smd rect
			(at 2.050034 -6.374892 90)
			(size 0.519938 1.4986)
			(layers "F.Cu" "F.Mask" "F.Paste")
			(net "GND")
		)
		(pad "213" smd rect
			(at 2.050034 -5.525008 90)
			(size 0.519938 1.4986)
			(layers "F.Cu" "F.Mask" "F.Paste")
			(net "M_B_CPU1_SA_CA<3>")
		)
		(pad "214" smd rect
			(at 2.050034 -4.675124 90)
			(size 0.519938 1.4986)
			(layers "F.Cu" "F.Mask" "F.Paste")
			(net "GND")
		)
		(pad "215" smd rect
			(at 2.050034 -3.824986 90)
			(size 0.519938 1.4986)
			(layers "F.Cu" "F.Mask" "F.Paste")
			(net "M_B_CPU1_SA_CA<5>")
		)
		(pad "216" smd rect
			(at 2.050034 -2.975102 90)
			(size 0.519938 1.4986)
			(layers "F.Cu" "F.Mask" "F.Paste")
			(net "GND")
		)
		(pad "217" smd rect
			(at 2.050034 -2.124964 90)
			(size 0.519938 1.4986)
			(layers "F.Cu" "F.Mask" "F.Paste")
			(net "M_B_CPU1_CLK_DP<0>")
		)
		(pad "218" smd rect
			(at 2.050034 -1.27508 90)
			(size 0.519938 1.4986)
			(layers "F.Cu" "F.Mask" "F.Paste")
			(net "M_B_CPU1_CLK_DN<0>")
		)
		(pad "219" smd rect
			(at 2.050034 -0.424942 90)
			(size 0.519938 1.4986)
			(layers "F.Cu" "F.Mask" "F.Paste")
			(net "GND")
		)
		(pad "220" smd rect
			(at 2.050034 5.525008 90)
			(size 0.519938 1.4986)
			(layers "F.Cu" "F.Mask" "F.Paste")
			(net "Net_2274")
		)
		(pad "221" smd rect
			(at 2.050034 6.374892 90)
			(size 0.519938 1.4986)
			(layers "F.Cu" "F.Mask" "F.Paste")
			(net "M_B_CPU1_SB_CA<1>")
		)
		(pad "222" smd rect
			(at 2.050034 7.22503 90)
			(size 0.519938 1.4986)
			(layers "F.Cu" "F.Mask" "F.Paste")
			(net "GND")
		)
		(pad "223" smd rect
			(at 2.050034 8.074914 90)
			(size 0.519938 1.4986)
			(layers "F.Cu" "F.Mask" "F.Paste")
			(net "M_B_CPU1_SB_CA<3>")
		)
		(pad "224" smd rect
			(at 2.050034 8.925052 90)
			(size 0.519938 1.4986)
			(layers "F.Cu" "F.Mask" "F.Paste")
			(net "GND")
		)
		(pad "225" smd rect
			(at 2.050034 9.774936 90)
			(size 0.519938 1.4986)
			(layers "F.Cu" "F.Mask" "F.Paste")
			(net "M_B_CPU1_SB_CA<5>")
		)
		(pad "226" smd rect
			(at 2.050034 10.625074 90)
			(size 0.519938 1.4986)
			(layers "F.Cu" "F.Mask" "F.Paste")
			(net "GND")
		)
	)
)
